(kicad_pcb
	(version 20260206)
	(generator "pcbnew")
	(generator_version "10.0")
	(general
		(thickness 1.6)
		(legacy_teardrops no)
	)
	(paper "A4")
	(title_block
		(title "Bryce Canyon_F.DPB_16315-1-OCP.brd")
		(comment 1 "Bryce Canyon / footprints 660-662 of 2223")
	)
	(layers
		(0 "F.Cu" signal "TOP")
		(4 "In1.Cu" signal "L2GND")
		(6 "In2.Cu" signal "L3")
		(8 "In3.Cu" signal "L4GND")
		(10 "In4.Cu" signal "L5")
		(12 "In5.Cu" signal "L6VCC")
		(14 "In6.Cu" signal "L7VCC")
		(16 "In7.Cu" signal "L8")
		(18 "In8.Cu" signal "L9GND")
		(20 "In9.Cu" signal "L10")
		(22 "In10.Cu" signal "L11GND")
		(2 "B.Cu" signal "BOTTOM")
		(9 "F.Adhes" user "F.Adhesive")
		(11 "B.Adhes" user "B.Adhesive")
		(13 "F.Paste" user "Package Geometry/Pastemask Top")
		(15 "B.Paste" user "Package Geometry/Pastemask Bottom")
		(5 "F.SilkS" user "Ref Des/Silkscreen Top")
		(7 "B.SilkS" user "Ref Des/Silkscreen Bottom")
		(1 "F.Mask" user "Board Geometry/Soldermask Top")
		(3 "B.Mask" user "Board Geometry/Soldermask Bottom")
		(17 "Dwgs.User" user "User.Drawings")
		(19 "Cmts.User" user "User.Comments")
		(21 "Eco1.User" user "User.Eco1")
		(23 "Eco2.User" user "User.Eco2")
		(25 "Edge.Cuts" user "Board Geometry/Outline")
		(27 "Margin" user)
		(31 "F.CrtYd" user "Package Geometry/Place Bound Top")
		(29 "B.CrtYd" user "Package Geometry/Place Bound Bottom")
		(35 "F.Fab" user "Ref Des/Assembly Top")
		(33 "B.Fab" user "Ref Des/Assembly Bottom")
	)
	(footprint ""
		(layer "F.Cu")
		(at 282.351734 20.532852 90)
		(property "Reference" "R1137"
			(at 0 0 90)
			(layer "F.SilkS")
			(hide yes)
			(effects
				(font
					(size 1.27 1.27)
				)
			)
		)
		(property "Value" "3K83R2F-GP"
			(at 0.064008 -3.993896 90)
			(unlocked yes)
			(layer "F.Fab")
			(hide yes)
			(effects
				(font
					(size 1.016 1.016)
					(thickness 0.1524)
				)
			)
		)
		(property "Device Type" "R402H16"
			(at 0.064008 -5.517896 90)
			(unlocked yes)
			(layer "F.Fab")
			(hide yes)
			(effects
				(font
					(size 1.016 1.016)
					(thickness 0.1524)
				)
			)
		)
		(duplicate_pad_numbers_are_jumpers no)
		(fp_line
			(start 0.508 -0.9398)
			(end -0.508 -0.9398)
			(stroke
				(width 0.1524)
				(type default)
			)
			(layer "F.SilkS")
		)
		(fp_line
			(start -0.508 -0.9398)
			(end -0.508 0.9398)
			(stroke
				(width 0.1524)
				(type default)
			)
			(layer "F.SilkS")
		)
		(fp_rect
			(start -0.508 0.9398)
			(end 0.508 -0.9398)
			(stroke
				(width 0)
				(type default)
			)
			(fill no)
			(layer "F.CrtYd")
		)
		(fp_rect
			(start -0.508 0.9398)
			(end 0.508 -0.9398)
			(stroke
				(width 0)
				(type default)
			)
			(fill no)
			(layer "F.Fab")
		)
		(pad "1" smd custom
			(at 0 -0.4445 90)
			(size 0.1397 0.1397)
			(layers "F.Cu" "F.Mask" "F.Paste")
			(net "DPB_PWR_BTN_B")
			(options
				(clearance outline)
				(anchor circle)
			)
			(primitives
				(gr_poly
					(pts
						(arc
							(start -0.1778 -0.2794)
							(mid -0.249642 -0.249642)
							(end -0.2794 -0.1778)
						)
						(arc
							(start -0.2794 0.1778)
							(mid -0.249642 0.249642)
							(end -0.1778 0.2794)
						)
						(arc
							(start 0.1778 0.2794)
							(mid 0.249642 0.249642)
							(end 0.2794 0.1778)
						)
						(arc
							(start 0.2794 -0.1778)
							(mid 0.249642 -0.249642)
							(end 0.1778 -0.2794)
						)
					)
					(width 0)
					(fill yes)
				)
			)
		)
		(pad "2" smd custom
			(at 0 0.4445 90)
			(size 0.1397 0.1397)
			(layers "F.Cu" "F.Mask" "F.Paste")
			(net "GND")
			(options
				(clearance outline)
				(anchor circle)
			)
			(primitives
				(gr_poly
					(pts
						(arc
							(start -0.1778 -0.2794)
							(mid -0.249642 -0.249642)
							(end -0.2794 -0.1778)
						)
						(arc
							(start -0.2794 0.1778)
							(mid -0.249642 0.249642)
							(end -0.1778 0.2794)
						)
						(arc
							(start 0.1778 0.2794)
							(mid 0.249642 0.249642)
							(end 0.2794 0.1778)
						)
						(arc
							(start 0.2794 -0.1778)
							(mid 0.249642 -0.249642)
							(end 0.1778 -0.2794)
						)
					)
					(width 0)
					(fill yes)
				)
			)
		)
	)
	(footprint ""
		(layer "F.Cu")
		(at 426.755052 -272.585942)
		(property "Reference" "R350"
			(at 0 0 0)
			(layer "F.SilkS")
			(hide yes)
			(effects
				(font
					(size 1.27 1.27)
				)
			)
		)
		(property "Value" "4K7R2J-2-GP"
			(at 0.064008 -3.993896 0)
			(unlocked yes)
			(layer "F.Fab")
			(hide yes)
			(effects
				(font
					(size 1.016 1.016)
					(thickness 0.1524)
				)
			)
		)
		(property "Device Type" "R402H16"
			(at 0.064008 -5.517896 0)
			(unlocked yes)
			(layer "F.Fab")
			(hide yes)
			(effects
				(font
					(size 1.016 1.016)
					(thickness 0.1524)
				)
			)
		)
		(duplicate_pad_numbers_are_jumpers no)
		(fp_line
			(start -0.508 -0.9398)
			(end -0.508 0.9398)
			(stroke
				(width 0.1524)
				(type default)
			)
			(layer "F.SilkS")
		)
		(fp_line
			(start 0.508 -0.9398)
			(end -0.508 -0.9398)
			(stroke
				(width 0.1524)
				(type default)
			)
			(layer "F.SilkS")
		)
		(fp_rect
			(start -0.508 0.9398)
			(end 0.508 -0.9398)
			(stroke
				(width 0)
				(type default)
			)
			(fill no)
			(layer "F.CrtYd")
		)
		(fp_rect
			(start -0.508 0.9398)
			(end 0.508 -0.9398)
			(stroke
				(width 0)
				(type default)
			)
			(fill no)
			(layer "F.Fab")
		)
		(pad "1" smd custom
			(at 0 -0.4445)
			(size 0.1397 0.1397)
			(layers "F.Cu" "F.Mask" "F.Paste")
			(net "SW_PWR_R_HDD9")
			(options
				(clearance outline)
				(anchor circle)
			)
			(primitives
				(gr_poly
					(pts
						(arc
							(start -0.1778 -0.2794)
							(mid -0.249642 -0.249642)
							(end -0.2794 -0.1778)
						)
						(arc
							(start -0.2794 0.1778)
							(mid -0.249642 0.249642)
							(end -0.1778 0.2794)
						)
						(arc
							(start 0.1778 0.2794)
							(mid 0.249642 0.249642)
							(end 0.2794 0.1778)
						)
						(arc
							(start 0.2794 -0.1778)
							(mid 0.249642 -0.249642)
							(end 0.1778 -0.2794)
						)
					)
					(width 0)
					(fill yes)
				)
			)
		)
		(pad "2" smd custom
			(at 0 0.4445)
			(size 0.1397 0.1397)
			(layers "F.Cu" "F.Mask" "F.Paste")
			(net "GND")
			(options
				(clearance outline)
				(anchor circle)
			)
			(primitives
				(gr_poly
					(pts
						(arc
							(start -0.1778 -0.2794)
							(mid -0.249642 -0.249642)
							(end -0.2794 -0.1778)
						)
						(arc
							(start -0.2794 0.1778)
							(mid -0.249642 0.249642)
							(end -0.1778 0.2794)
						)
						(arc
							(start 0.1778 0.2794)
							(mid 0.249642 0.249642)
							(end 0.2794 0.1778)
						)
						(arc
							(start 0.2794 -0.1778)
							(mid 0.249642 -0.249642)
							(end 0.1778 -0.2794)
						)
					)
					(width 0)
					(fill yes)
				)
			)
		)
	)
	(footprint ""
		(layer "F.Cu")
		(at 272.91157 -371.731794)
		(property "Reference" "R1172"
			(at 0 0 0)
			(layer "F.SilkS")
			(hide yes)
			(effects
				(font
					(size 1.27 1.27)
				)
			)
		)
		(property "Value" "10R5F-1-GP"
			(at 0 -8.9535 0)
			(unlocked yes)
			(layer "F.Fab")
			(hide yes)
			(effects
				(font
					(size 1.27 1.016)
					(thickness 0.1524)
				)
			)
		)
		(property "Device Type" "R805H24"
			(at 0 -10.6299 0)
			(unlocked yes)
			(layer "F.Fab")
			(hide yes)
			(effects
				(font
					(size 1.27 1.016)
					(thickness 0.1524)
				)
			)
		)
		(duplicate_pad_numbers_are_jumpers no)
		(fp_line
			(start -0.889 -1.7018)
			(end -0.889 0.2794)
			(stroke
				(width 0.1524)
				(type default)
			)
			(layer "F.SilkS")
		)
		(fp_line
			(start -0.889 0.0762)
			(end -0.889 1.7018)
			(stroke
				(width 0.1524)
				(type default)
			)
			(layer "F.SilkS")
		)
		(fp_line
			(start -0.889 1.7018)
			(end 0.889 1.7018)
			(stroke
				(width 0.1524)
				(type default)
			)
			(layer "F.SilkS")
		)
		(fp_line
			(start 0.889 -1.7018)
			(end -0.889 -1.7018)
			(stroke
				(width 0.1524)
				(type default)
			)
			(layer "F.SilkS")
		)
		(fp_line
			(start 0.889 -1.7018)
			(end 0.889 -0.381)
			(stroke
				(width 0.1524)
				(type default)
			)
			(layer "F.SilkS")
		)
		(fp_line
			(start 0.889 1.7018)
			(end 0.889 -0.508)
			(stroke
				(width 0.1524)
				(type default)
			)
			(layer "F.SilkS")
		)
		(fp_poly
			(pts
				(xy 0.9652 -1.778) (xy 0.9652 1.778) (xy -0.9652 1.778) (xy -0.9652 -1.778)
			)
			(stroke
				(width 0)
				(type default)
			)
			(fill no)
			(layer "F.CrtYd")
		)
		(fp_rect
			(start -0.9652 1.778)
			(end 0.9652 -1.778)
			(stroke
				(width 0)
				(type default)
			)
			(fill no)
			(layer "F.Fab")
		)
		(pad "1" smd rect
			(at 0 -0.9652)
			(size 1.397 1.143)
			(layers "F.Cu" "F.Mask" "F.Paste")
			(net "MB3_12V_CTRL_GATE1")
		)
		(pad "2" smd rect
			(at 0 0.9652)
			(size 1.397 1.143)
			(layers "F.Cu" "F.Mask" "F.Paste")
			(net "MB3_CM_GATE_R")
		)
	)
)
